G04 ================== begin FILE IDENTIFICATION RECORD ==================*
G04 Layout Name:  15750-1.brd*
G04 Film Name:    L7GND*
G04 File Format:  Gerber RS274X*
G04 File Origin:  Cadence Allegro 16.5-S056*
G04 Origin Date:  Fri Dec 30 13:21:40 2016*
G04 *
G04 Layer:  VIA CLASS/L7GND*
G04 Layer:  PIN/L7GND*
G04 Layer:  ETCH/L7GND*
G04 Layer:  DRAWING FORMAT/LAYER_L7GND*
G04 Layer:  DRAWING FORMAT/LAYER_PCB_STORY*
G04 *
G04 Offset:    (0.00 0.00)*
G04 Mirror:    No*
G04 Mode:      Negative*
G04 Rotation:  0*
G04 FullContactRelief:  No*
G04 UndefLineWidth:     6.00*
G04 ================== end FILE IDENTIFICATION RECORD ====================*
%FSLAX35Y35*MOIN*%
%IR0*IPPOS*OFA0.00000B0.00000*MIA0B0*SFA1.00000B1.00000*%
%ADD15C,.03*%
%ADD14C,.032*%
%ADD17C,.072*%
%ADD16C,.091*%
%ADD20C,.093*%
%ADD18C,.068*%
%AMMACRO12*
4,1,15,.00398,.00044,
.003999,.000208,
.004004,-.000025,
.003996,-.000258,
.00398,-.00044,
.00483,-.00129,
.004897,-.001007,
.004947,-.000721,
.004981,-.000432,
.004997,-.000141,
.004997,.000149,
.00498,.00044,
.004946,.000729,
.004895,.001015,
.00483,.00129,
.00398,.00044,
0.0*
4,1,15,.00044,-.00398,
.000208,-.003999,
-.000025,-.004004,
-.000258,-.003996,
-.00044,-.00398,
-.00129,-.00483,
-.001007,-.004897,
-.000721,-.004947,
-.000432,-.004981,
-.000141,-.004997,
.000149,-.004997,
.00044,-.00498,
.000729,-.004946,
.001015,-.004895,
.00129,-.00483,
.00044,-.00398,
0.0*
4,1,15,-.00398,-.00044,
-.003999,-.000208,
-.004004,.000025,
-.003996,.000258,
-.00398,.00044,
-.00483,.00129,
-.004897,.001007,
-.004947,.000721,
-.004981,.000432,
-.004997,.000141,
-.004997,-.000149,
-.00498,-.00044,
-.004946,-.000729,
-.004895,-.001015,
-.00483,-.00129,
-.00398,-.00044,
0.0*
4,1,15,-.00044,.00398,
-.000208,.003999,
.000025,.004004,
.000258,.003996,
.00044,.00398,
.00129,.00483,
.001007,.004897,
.000721,.004947,
.000432,.004981,
.000141,.004997,
-.000149,.004997,
-.00044,.00498,
-.000729,.004946,
-.001015,.004895,
-.00129,.00483,
-.00044,.00398,
0.0*
%
%ADD12MACRO12*%
%AMMACRO19*
4,1,13,.02632,.01218,
.028035,.007425,
.028899,.002443,
.028884,-.002612,
.027991,-.007588,
.02632,-.01218,
.03005,-.01591,
.032356,-.01045,
.033679,-.004673,
.033979,.001247,
.033246,.007128,
.031504,.012793,
.03005,.01591,
.02632,.01218,
270.*
4,1,13,.01218,-.02632,
.007425,-.028035,
.002443,-.028899,
-.002612,-.028884,
-.007588,-.027991,
-.01218,-.02632,
-.01591,-.03005,
-.01045,-.032356,
-.004673,-.033679,
.001247,-.033979,
.007128,-.033246,
.012793,-.031504,
.01591,-.03005,
.01218,-.02632,
270.*
4,1,13,-.02632,-.01218,
-.028035,-.007425,
-.028899,-.002443,
-.028884,.002612,
-.027991,.007588,
-.02632,.01218,
-.03005,.01591,
-.032356,.01045,
-.033679,.004673,
-.033979,-.001247,
-.033246,-.007128,
-.031504,-.012793,
-.03005,-.01591,
-.02632,-.01218,
270.*
4,1,13,-.01218,.02632,
-.007425,.028035,
-.002443,.028899,
.002612,.028884,
.007588,.027991,
.01218,.02632,
.01591,.03005,
.01045,.032356,
.004673,.033679,
-.001247,.033979,
-.007128,.033246,
-.012793,.031504,
-.01591,.03005,
-.01218,.02632,
270.*
%
%ADD19MACRO19*%
%ADD10C,.114*%
%AMMACRO13*
4,1,15,.00398,.00044,
.003999,.000208,
.004004,-.000025,
.003996,-.000258,
.00398,-.00044,
.00483,-.00129,
.004897,-.001007,
.004947,-.000721,
.004981,-.000432,
.004997,-.000141,
.004997,.000149,
.00498,.00044,
.004946,.000729,
.004895,.001015,
.00483,.00129,
.00398,.00044,
270.*
4,1,15,.00044,-.00398,
.000208,-.003999,
-.000025,-.004004,
-.000258,-.003996,
-.00044,-.00398,
-.00129,-.00483,
-.001007,-.004897,
-.000721,-.004947,
-.000432,-.004981,
-.000141,-.004997,
.000149,-.004997,
.00044,-.00498,
.000729,-.004946,
.001015,-.004895,
.00129,-.00483,
.00044,-.00398,
270.*
4,1,15,-.00398,-.00044,
-.003999,-.000208,
-.004004,.000025,
-.003996,.000258,
-.00398,.00044,
-.00483,.00129,
-.004897,.001007,
-.004947,.000721,
-.004981,.000432,
-.004997,.000141,
-.004997,-.000149,
-.00498,-.00044,
-.004946,-.000729,
-.004895,-.001015,
-.00483,-.00129,
-.00398,-.00044,
270.*
4,1,15,-.00044,.00398,
-.000208,.003999,
.000025,.004004,
.000258,.003996,
.00044,.00398,
.00129,.00483,
.001007,.004897,
.000721,.004947,
.000432,.004981,
.000141,.004997,
-.000149,.004997,
-.00044,.00498,
-.000729,.004946,
-.001015,.004895,
-.00129,.00483,
-.00044,.00398,
270.*
%
%ADD13MACRO13*%
%AMMACRO11*
4,1,16,.07256,.04427,
.079145,.030998,
.083325,.016783,
.084974,.002059,
.08404,-.012728,
.080553,-.027128,
.074619,-.040704,
.07256,-.04427,
.07619,-.04791,
.083352,-.033952,
.087981,-.018962,
.089937,-.003396,
.089161,.012273,
.085675,.027569,
.079586,.042027,
.07619,.04791,
.07256,.04427,
0.0*
4,1,16,.04427,-.07256,
.030998,-.079145,
.016783,-.083325,
.002059,-.084974,
-.012728,-.08404,
-.027128,-.080553,
-.040704,-.074619,
-.04427,-.07256,
-.04791,-.07619,
-.033952,-.083352,
-.018962,-.087981,
-.003396,-.089937,
.012273,-.089161,
.027569,-.085675,
.042027,-.079586,
.04791,-.07619,
.04427,-.07256,
0.0*
4,1,16,-.07256,-.04427,
-.079145,-.030998,
-.083325,-.016783,
-.084974,-.002059,
-.08404,.012728,
-.080553,.027128,
-.074619,.040704,
-.07256,.04427,
-.07619,.04791,
-.083352,.033952,
-.087981,.018962,
-.089937,.003396,
-.089161,-.012273,
-.085675,-.027569,
-.079586,-.042027,
-.07619,-.04791,
-.07256,-.04427,
0.0*
4,1,16,-.04427,.07256,
-.030998,.079145,
-.016783,.083325,
-.002059,.084974,
.012728,.08404,
.027128,.080553,
.040704,.074619,
.04427,.07256,
.04791,.07619,
.033952,.083352,
.018962,.087981,
.003396,.089937,
-.012273,.089161,
-.027569,.085675,
-.042027,.079586,
-.04791,.07619,
-.04427,.07256,
0.0*
%
%ADD11MACRO11*%
%ADD21C,.02*%
%ADD22C,.006*%
%ADD25C,.06804*%
%ADD24C,.08704*%
%ADD27C,.08904*%
%ADD23O,.04824X.09264*%
%ADD26R,.03748X.08276*%
G75*
%LPD*%
G75*
G36*
G01X-6000Y-6000D02*
X355409D01*
Y369425D01*
X-6000D01*
Y-6000D01*
G37*
%LPC*%
G75*
G36*
G01X223819Y1904D02*
G02X217849Y7874I0J5970D01*
G01Y258071D01*
G03X208071Y267849I-9778J0D01*
G01X7874D01*
G02X1904Y273819I0J5970D01*
G01Y355551D01*
G02X7874Y361521I5970J0D01*
G01X341535D01*
G02X347505Y355551I0J-5970D01*
G01Y278779D01*
G02X347441Y278715I-64J0D01*
G01X339566D01*
G03X335694Y274843I1J-3873D01*
G01Y219567D01*
G03X339567Y215694I3873J0D01*
G01X347441D01*
G02X347505Y215630I0J-64D01*
G01Y195925D01*
G02X347441Y195861I-64J0D01*
G01X321062D01*
G03X317190Y191989I1J-3873D01*
G01Y175256D01*
G03X319956Y171545I3873J0D01*
G01X320098Y171502D01*
Y164286D01*
X323846D01*
Y164807D01*
G02X324454Y165148I400J0D01*
G03X325720Y165002I790J1289D01*
G02X326246Y164623I126J-379D01*
G01Y161952D01*
G02X325720Y161573I-400J0D01*
G03X324454Y161427I-476J-1435D01*
G02X323846Y161768I-208J341D01*
G01Y162290D01*
X316942D01*
Y154838D01*
X323846D01*
Y155358D01*
G02X324454Y155699I400J0D01*
G03X325720Y155553I790J1289D01*
G02X326246Y155174I126J-379D01*
G01Y152502D01*
G02X325720Y152122I-400J0D01*
G03X324455Y151976I-476J-1433D01*
G02X323846Y152317I-209J341D01*
G01Y152840D01*
X316942D01*
Y145388D01*
X323846D01*
Y145912D01*
G02X324455Y146253I400J0D01*
G03X325720Y146107I789J1287D01*
G02X326246Y145727I126J-380D01*
G01Y111558D01*
G02X325720Y111179I-400J0D01*
G03X324454Y111033I-476J-1435D01*
G02X323846Y111374I-208J341D01*
G01Y111896D01*
X316942D01*
Y104444D01*
X323846D01*
Y104965D01*
G02X324454Y105306I400J0D01*
G03X325720Y105160I790J1289D01*
G02X326246Y104781I126J-379D01*
G01Y102110D01*
G02X325720Y101731I-400J0D01*
G03X324454Y101585I-476J-1435D01*
G02X323846Y101926I-208J341D01*
G01Y102446D01*
X316942D01*
Y94994D01*
X323846D01*
Y95516D01*
G02X324454Y95857I400J0D01*
G03X325720Y95711I790J1289D01*
G02X326246Y95332I126J-379D01*
G01Y92661D01*
G02X325720Y92282I-400J0D01*
G03X324454Y92136I-476J-1435D01*
G02X323846Y92477I-208J341D01*
G01Y92998D01*
X316942D01*
Y85546D01*
X323846D01*
Y86067D01*
G02X324454Y86408I400J0D01*
G03X325720Y86262I790J1289D01*
G02X326246Y85883I126J-379D01*
G01Y83212D01*
G02X325720Y82833I-400J0D01*
G03X324454Y82687I-476J-1435D01*
G02X323846Y83028I-208J341D01*
G01Y83550D01*
X316942D01*
Y76098D01*
X323846D01*
Y76618D01*
G02X324454Y76959I400J0D01*
G03X325720Y76813I790J1289D01*
G02X326246Y76434I126J-379D01*
G01Y73763D01*
G02X325720Y73384I-400J0D01*
G03X324454Y73238I-476J-1435D01*
G02X323846Y73579I-208J341D01*
G01Y74100D01*
X316942D01*
Y66648D01*
X323846D01*
Y67169D01*
G02X324454Y67510I400J0D01*
G03X325720Y67364I790J1289D01*
G02X326246Y66985I126J-379D01*
G01Y64314D01*
G02X325720Y63935I-400J0D01*
G03X324454Y63789I-476J-1435D01*
G02X323846Y64130I-208J341D01*
G01Y64652D01*
X316942D01*
Y57200D01*
X323846D01*
Y57721D01*
G02X324454Y58062I400J0D01*
G03X325720Y57916I790J1289D01*
G02X326246Y57537I126J-379D01*
G01Y46004D01*
G02X326181Y45939I-65J0D01*
G01X321062D01*
G03X317190Y42067I1J-3873D01*
G01Y25334D01*
G03X321062Y21462I3873J1D01*
G01X347441D01*
G02X347505Y21398I0J-64D01*
G01Y1968D01*
G02X347441Y1904I-64J0D01*
G01X223819D01*
G37*
%LPD*%
G75*
G36*
G01X289288Y198561D02*
G02X293312I2012J0D01*
G01Y195360D01*
G02X289288Y195361I-2012J1D01*
G01Y198561D01*
G37*
G36*
G01X300388Y137043D02*
G02X305212I2412J0D01*
G01Y132642D01*
G02X300388Y132643I-2412J1D01*
G01Y137043D01*
G37*
G36*
G01X292988Y89899D02*
G02X297012I2012J0D01*
G01Y86698D01*
G02X292988Y86699I-2012J1D01*
G01Y89899D01*
G37*
G36*
G01X277512Y222811D02*
Y218371D01*
G02X272688Y218372I-2412J1D01*
G01Y222812D01*
G02X277512Y222811I2412J-1D01*
G37*
G36*
G01X275512Y211000D02*
Y206560D01*
G02X270688Y206561I-2412J1D01*
G01Y211001D01*
G02X275512Y211000I2412J-1D01*
G37*
G36*
G01Y102339D02*
Y97898D01*
G02X270688Y97899I-2412J1D01*
G01Y102339D01*
G02X275512I2412J0D01*
G37*
G54D25*
X265551Y143464D03*
Y252126D03*
G54D24*
Y64724D03*
Y173386D03*
X311614Y31870D03*
G54D27*
Y185414D03*
G54D23*
X275100Y111930D03*
G54D26*
X308540Y135256D03*
G54D15*
X95000Y277500D03*
X99000D03*
X106500D03*
X92500Y295000D03*
X106137Y286000D03*
X100000Y288500D03*
X92500Y298500D03*
Y309000D03*
X107000Y311500D03*
Y308000D03*
X100250Y313200D03*
X103500Y317000D03*
Y321000D03*
X91500Y312500D03*
X96750Y328500D03*
X100500Y347289D03*
X121500Y276500D03*
X118000D03*
X114500D03*
X110500Y277500D03*
X121456Y289154D03*
X112500Y289000D03*
X108000Y295000D03*
Y298500D03*
X115000Y305000D03*
X119000D03*
X108000Y303100D03*
X120120Y315000D03*
X116500D03*
X109500Y334500D03*
X113000D03*
X117000D03*
X121000D03*
X125000Y277000D03*
X128500Y282500D03*
X126000Y287000D03*
X130000Y298500D03*
X215064Y316100D03*
X237000Y156000D03*
Y159780D03*
Y152500D03*
X236500Y168500D03*
X225000Y169500D03*
X237000Y164250D03*
X251000Y88500D03*
X252000Y151500D03*
Y155000D03*
Y160500D03*
X251000Y197000D03*
X263000Y96500D03*
Y88500D03*
Y81338D03*
Y84838D03*
Y104000D03*
X262819Y100157D03*
X268140Y161221D03*
X258750Y168000D03*
X263000Y190000D03*
Y193500D03*
Y205000D03*
Y197000D03*
Y212500D03*
X262819Y208819D03*
X263000Y240315D03*
X275100Y109710D03*
X273100Y102299D03*
Y97899D03*
X275100Y114110D03*
X279000Y166000D03*
X273100Y210961D03*
Y206561D03*
X275100Y222772D03*
Y218372D03*
X295000Y86699D03*
Y89899D03*
X301000Y125000D03*
X292000Y126000D03*
X302800Y137043D03*
Y132643D03*
X290500Y154250D03*
X296500Y157500D03*
X290500Y150750D03*
X291000Y169500D03*
X291300Y195361D03*
Y198561D03*
X325244Y49902D03*
Y53051D03*
Y62500D03*
Y59351D03*
Y78248D03*
Y68799D03*
Y71949D03*
Y97146D03*
Y87697D03*
Y90847D03*
Y81398D03*
Y106595D03*
Y109744D03*
Y100296D03*
Y156988D03*
Y160138D03*
Y150689D03*
Y147540D03*
Y166437D03*
Y169587D03*
G54D14*
X72000Y286000D03*
Y290000D03*
X58000Y310689D03*
X79000Y344000D03*
Y348000D03*
X138500Y299500D03*
X134500Y307500D03*
X138500Y303500D03*
Y307500D03*
X137500Y324500D03*
X142500Y299500D03*
Y303500D03*
Y307500D03*
X141811Y324500D03*
X145811D03*
X153811D03*
X149811D03*
X162311Y293000D03*
X160811Y310000D03*
X169811Y309500D03*
X172311Y305500D03*
X157811Y324500D03*
X161811D03*
X169811D03*
X165811D03*
X169811Y313500D03*
X176311Y294000D03*
X181061Y297750D03*
X176168Y305500D03*
X195811Y296000D03*
X200811Y308000D03*
Y311000D03*
Y317000D03*
Y314000D03*
X218000Y292000D03*
X215811Y300000D03*
X222311Y325000D03*
X218311D03*
X230000Y96500D03*
X225000Y205000D03*
X222911Y287089D03*
X247000Y68838D03*
Y72838D03*
X251000Y68838D03*
Y72838D03*
X247000Y123838D03*
X251000D03*
X247000Y127838D03*
X251000D03*
X247000Y136338D03*
Y140838D03*
X251000D03*
Y136338D03*
Y177500D03*
X247000D03*
X251000Y181500D03*
X247000D03*
X251000Y245000D03*
X247000D03*
X251000Y236500D03*
X247000D03*
X251000Y232500D03*
X247000D03*
X251000Y249500D03*
X247000D03*
X242500Y294000D03*
X246500D03*
X250500D03*
X242500Y306000D03*
Y302000D03*
Y298000D03*
X246500Y306000D03*
Y302000D03*
Y298000D03*
X250500D03*
Y302000D03*
Y306000D03*
X262920Y131653D03*
X273000Y92283D03*
X299500Y46000D03*
X303500D03*
X296500Y61000D03*
X300500D03*
X301500Y49000D03*
X297500D03*
X295500Y52000D03*
X299500D03*
X295500Y110000D03*
X295311Y127600D03*
X304500Y123820D03*
X301711Y245000D03*
G54D17*
X265551Y143464D03*
Y252126D03*
G54D16*
Y64724D03*
Y173386D03*
X311614Y31870D03*
G54D20*
Y185414D03*
G54D18*
X302000Y290500D03*
Y300500D03*
G54D12*
X10000Y330000D03*
Y345000D03*
Y360000D03*
X40000Y270000D03*
Y285000D03*
Y300000D03*
Y330000D03*
Y345000D03*
X25000Y360000D03*
X40000D03*
X55000Y270000D03*
Y285000D03*
Y360000D03*
X70000Y270000D03*
Y360000D03*
X85000Y270000D03*
Y360000D03*
X100000Y270000D03*
X103000Y277500D03*
X96750Y313250D03*
X103750Y313200D03*
X100500Y335689D03*
X100000Y360000D03*
X122100Y280750D03*
X122000Y301000D03*
X115000Y360000D03*
X124000Y315000D03*
X138000Y341500D03*
X130000Y360000D03*
X138000Y345500D03*
X140500Y281000D03*
X146500Y303500D03*
X150500D03*
X146500Y307500D03*
X150500D03*
X155000Y301350D03*
X149811Y341500D03*
X141811D03*
X145811D03*
X153811D03*
X145000Y360000D03*
X149811Y345500D03*
X141811D03*
X145811D03*
X153811D03*
X164811Y304000D03*
X165811Y341500D03*
X157811D03*
X161811D03*
X169811D03*
X160000Y360000D03*
X165811Y345500D03*
X169811D03*
X157811D03*
X161811D03*
X185811Y304200D03*
Y310500D03*
X181811D03*
Y318500D03*
X185811Y314500D03*
Y326500D03*
Y322500D03*
Y318500D03*
X181811Y326500D03*
Y322500D03*
Y314500D03*
X184500Y334000D03*
Y338000D03*
X175000Y360000D03*
X189811Y310500D03*
Y318500D03*
Y322500D03*
Y326500D03*
Y314500D03*
X190000Y360000D03*
X205000D03*
X220000D03*
X225000Y35000D03*
Y50000D03*
Y80000D03*
Y65000D03*
X230000Y75000D03*
Y67000D03*
Y71000D03*
X225000Y95000D03*
Y110000D03*
X230000Y126000D03*
Y130000D03*
Y122000D03*
Y138500D03*
Y142500D03*
Y134500D03*
X236805Y146452D03*
X225000Y160250D03*
Y149250D03*
Y164250D03*
X230000Y175500D03*
Y179500D03*
Y183500D03*
Y243000D03*
Y234500D03*
Y238500D03*
Y230500D03*
Y247000D03*
Y251000D03*
X237500Y340000D03*
Y344000D03*
Y336000D03*
X235000Y360000D03*
X255000Y5000D03*
Y35000D03*
X251500Y164500D03*
X249000Y260000D03*
X241500Y336000D03*
Y344000D03*
Y340000D03*
X250000Y360000D03*
X270000Y5000D03*
Y35000D03*
X269650Y97899D03*
X271650Y109710D03*
X269650Y102299D03*
X271650Y114110D03*
X271250Y138750D03*
X267700Y153250D03*
X269650Y210961D03*
Y206561D03*
X271650Y222772D03*
Y218372D03*
X265000Y270000D03*
Y285000D03*
X271500Y294000D03*
X267500D03*
X271500Y306000D03*
Y302000D03*
Y298000D03*
X267500D03*
Y302000D03*
Y306000D03*
X260500Y340000D03*
Y344000D03*
Y336000D03*
X256500D03*
Y344000D03*
Y340000D03*
X265000Y360000D03*
X282500Y5000D03*
X272500Y20000D03*
X285000Y32500D03*
X275500Y63346D03*
X280000Y71614D03*
Y67677D03*
X280169Y126732D03*
Y120826D03*
X275768Y144842D03*
X280169Y138543D03*
Y132637D03*
X278860Y162250D03*
X280000Y176339D03*
X275500Y172008D03*
X280000Y180276D03*
X273500Y194055D03*
Y199961D03*
X273600Y240250D03*
X280169Y247205D03*
X275768Y253504D03*
X280000Y270000D03*
X275500Y294000D03*
X280000Y285000D03*
X275500Y298000D03*
Y302000D03*
Y306000D03*
X280000Y300000D03*
Y315000D03*
X295000Y5000D03*
X300000Y20000D03*
Y35000D03*
X304565Y61142D03*
Y96142D03*
X304500Y92000D03*
X291500Y97204D03*
X291550Y91299D03*
X291500Y85393D03*
X295500Y100000D03*
X291500Y109960D03*
Y101960D03*
Y114921D03*
X300500Y129100D03*
X299300Y137043D03*
X304565Y141142D03*
X299300Y132643D03*
X302000Y157500D03*
X292000Y181500D03*
X294750Y195261D03*
X295500Y208461D03*
X294750Y198661D03*
X291500Y210961D03*
Y205866D03*
Y218461D03*
Y223583D03*
Y241299D03*
Y229488D03*
Y235394D03*
X295000Y270000D03*
Y285000D03*
Y300000D03*
Y315000D03*
X315000Y5000D03*
Y20000D03*
Y40000D03*
X313000Y179500D03*
X310000Y225000D03*
Y240000D03*
Y255000D03*
Y270000D03*
Y285000D03*
Y300000D03*
Y315000D03*
Y330000D03*
Y360000D03*
Y345000D03*
X325244Y56201D03*
Y75099D03*
Y65650D03*
Y93996D03*
Y84548D03*
Y112894D03*
Y103445D03*
Y128642D03*
Y119193D03*
Y144390D03*
Y138091D03*
Y153839D03*
Y163288D03*
X324302Y203977D03*
X325000Y225000D03*
Y240000D03*
Y255000D03*
Y270000D03*
Y285000D03*
Y300000D03*
Y315000D03*
Y330000D03*
Y360000D03*
Y345000D03*
X345000Y5000D03*
Y20000D03*
X340000Y285000D03*
Y300000D03*
Y315000D03*
Y330000D03*
Y360000D03*
Y345000D03*
G54D19*
X302000Y310500D03*
G54D10*
X26087Y-114844D03*
X26435Y373984D03*
X175335Y62719D03*
Y189062D03*
X547104Y69007D03*
Y195351D03*
X696192Y373984D03*
G54D13*
X52500Y325189D03*
Y331189D03*
X59500Y294189D03*
X64500Y309589D03*
X59500Y299939D03*
X71500Y315689D03*
X67900D03*
X72000Y336689D03*
X89000Y295189D03*
Y291189D03*
Y287189D03*
Y283189D03*
Y303689D03*
Y299689D03*
X75100Y315689D03*
X89000Y329189D03*
Y333189D03*
G54D11*
X25596Y316176D03*
X237013Y17712D03*
X287407Y345704D03*
%LPC*%
G75*
G54D21*
G01X-176139Y-183003D02*
G02I-12000J0D01*
G01X-181289D02*
G02I-6850J0D01*
G01X-172139D02*
X-204139D01*
G01X-188139Y-199003D02*
Y-167003D01*
G01X-172139Y-199003D02*
Y-279003D01*
G01D02*
X1178561D01*
G01X-172139Y-234503D02*
X1178561D01*
G01X-172139Y-199003D02*
X1178561D01*
G01X391061D02*
Y-279003D01*
G01X528561Y-199003D02*
Y-279003D01*
G01X643561Y-199003D02*
Y-279003D01*
G01X811061Y-199003D02*
Y-279003D01*
G01X981061Y-199003D02*
Y-279003D01*
G01X1178561Y-199003D02*
Y-279003D01*
G01X1210561Y-183003D02*
X1178561D01*
G01X1206561D02*
G02I-12000J0D01*
G01X1201411D02*
G02I-6850J0D01*
G01X1194561Y-199003D02*
Y-167003D01*
G54D22*
G01X-148956Y-251503D02*
Y-269003D01*
X-140222D01*
G01X-127089Y-257337D02*
Y-269003D01*
G01Y-252670D02*
X-127526Y-252378D01*
Y-251795D01*
X-127089Y-251503D01*
X-126652Y-251795D01*
Y-252378D01*
X-127089Y-252670D01*
G01X-112646Y-273378D02*
X-111117Y-274545D01*
X-109371Y-274836D01*
X-107843Y-274545D01*
X-106532Y-273087D01*
X-105659Y-271045D01*
Y-257337D01*
G01Y-259670D02*
X-106532Y-258503D01*
X-107843Y-257628D01*
X-109371Y-257337D01*
X-111117Y-257920D01*
X-112209Y-259086D01*
X-113083Y-261128D01*
X-113519Y-263170D01*
X-113301Y-264920D01*
X-112427Y-266962D01*
X-111117Y-268420D01*
X-109371Y-269003D01*
X-108061Y-268711D01*
X-106532Y-267545D01*
X-105659Y-266379D01*
G01X-95801Y-269003D02*
Y-251503D01*
G01Y-259961D02*
X-94709Y-258503D01*
X-93617Y-257628D01*
X-91871Y-257337D01*
X-90561Y-257628D01*
X-89032Y-258795D01*
X-88377Y-260545D01*
Y-269003D01*
G01X-74589Y-251503D02*
Y-269003D01*
G01X-77646Y-257337D02*
X-71532D01*
G01X-60801Y-269003D02*
Y-257337D01*
G01Y-260253D02*
X-59927Y-258795D01*
X-58617Y-257628D01*
X-56871Y-257337D01*
X-55343Y-257628D01*
X-54032Y-258795D01*
X-53377Y-260836D01*
Y-269003D01*
G01X-39589Y-257337D02*
Y-269003D01*
G01Y-252670D02*
X-40026Y-252378D01*
Y-251795D01*
X-39589Y-251503D01*
X-39152Y-251795D01*
Y-252378D01*
X-39589Y-252670D01*
G01X-25801Y-269003D02*
Y-257337D01*
G01Y-260253D02*
X-24927Y-258795D01*
X-23617Y-257628D01*
X-21871Y-257337D01*
X-20343Y-257628D01*
X-19032Y-258795D01*
X-18377Y-260836D01*
Y-269003D01*
G01X-7646Y-273378D02*
X-6117Y-274545D01*
X-4371Y-274836D01*
X-2843Y-274545D01*
X-1532Y-273087D01*
X-659Y-271045D01*
Y-257337D01*
G01Y-259670D02*
X-1532Y-258503D01*
X-2843Y-257628D01*
X-4371Y-257337D01*
X-6117Y-257920D01*
X-7209Y-259086D01*
X-8083Y-261128D01*
X-8519Y-263170D01*
X-8301Y-264920D01*
X-7427Y-266962D01*
X-6117Y-268420D01*
X-4371Y-269003D01*
X-3061Y-268711D01*
X-1532Y-267545D01*
X-659Y-266379D01*
G01X26044Y-269003D02*
Y-251503D01*
X31284D01*
X33031Y-252378D01*
X34341Y-254420D01*
X34778Y-256753D01*
X34341Y-259086D01*
X33249Y-260836D01*
X31284Y-261712D01*
X26044D01*
G01X42452Y-251503D02*
X47911Y-269003D01*
X53370Y-251503D01*
G01X65411D02*
Y-269003D01*
G01X60389Y-251503D02*
X70433D01*
G01X94734Y-269003D02*
Y-251503D01*
X100411Y-266086D01*
X106088Y-251503D01*
Y-269003D01*
G01X117911Y-269586D02*
X117474Y-269295D01*
Y-268711D01*
X117911Y-268420D01*
X118348Y-268711D01*
Y-269295D01*
X117911Y-269586D01*
G01X131263Y-254420D02*
X132573Y-252670D01*
X134101Y-251795D01*
X135848Y-251503D01*
X138031Y-252086D01*
X139559Y-253545D01*
X139996Y-255294D01*
X139778Y-257045D01*
X138904Y-258503D01*
X134538Y-261420D01*
X132573Y-263461D01*
X131263Y-266379D01*
X130826Y-269003D01*
X139996D01*
G01X164952D02*
X170411Y-251503D01*
X175870Y-269003D01*
G01X173904Y-262878D02*
X166917D01*
G01X191841Y-251503D02*
Y-269003D01*
G01Y-266379D02*
X190968Y-267837D01*
X189657Y-268711D01*
X188129Y-269003D01*
X186383Y-268420D01*
X185073Y-266962D01*
X184199Y-265212D01*
X183981Y-263170D01*
X184199Y-261128D01*
X185073Y-259378D01*
X186383Y-257920D01*
X188129Y-257337D01*
X189657Y-257628D01*
X190749Y-258212D01*
X191841Y-259378D01*
G01X209341Y-269003D02*
Y-257337D01*
G01Y-259378D02*
X208468Y-258212D01*
X207157Y-257628D01*
X205629Y-257337D01*
X204101Y-257920D01*
X202791Y-259086D01*
X201917Y-260836D01*
X201481Y-263170D01*
X201917Y-265503D01*
X202791Y-267253D01*
X204101Y-268420D01*
X205629Y-269003D01*
X207157Y-268711D01*
X208468Y-267837D01*
X209341Y-266670D01*
G01X218981Y-274836D02*
Y-257337D01*
G01Y-259961D02*
X220073Y-258503D01*
X221164Y-257628D01*
X222911Y-257337D01*
X224439Y-257628D01*
X225968Y-259086D01*
X226623Y-261128D01*
X226841Y-263170D01*
X226623Y-265212D01*
X225968Y-267253D01*
X224657Y-268420D01*
X222911Y-269003D01*
X221383Y-268711D01*
X219854Y-267837D01*
X218981Y-266670D01*
G01X240411Y-251503D02*
Y-269003D01*
G01X237354Y-257337D02*
X243468D01*
G01X257911Y-269003D02*
X256601Y-268711D01*
X255291Y-267545D01*
X254417Y-265503D01*
X253981Y-263170D01*
X254417Y-260836D01*
X255291Y-258795D01*
X256601Y-257628D01*
X257911Y-257337D01*
X259221Y-257628D01*
X260531Y-258795D01*
X261404Y-260836D01*
X261623Y-263170D01*
X261404Y-265503D01*
X260531Y-267545D01*
X259221Y-268711D01*
X257911Y-269003D01*
G01X272354D02*
Y-257337D01*
G01Y-259670D02*
X273446Y-258503D01*
X274538Y-257628D01*
X276066Y-257337D01*
X277157Y-257628D01*
X278468Y-258503D01*
G01X315214Y-252962D02*
X313904Y-252086D01*
X312376Y-251503D01*
X310629D01*
X308664Y-252378D01*
X307136Y-253836D01*
X306044Y-255587D01*
X305171Y-258503D01*
X304952Y-261128D01*
X305389Y-263753D01*
X306044Y-265503D01*
X307354Y-267253D01*
X308883Y-268420D01*
X310411Y-269003D01*
X311939D01*
X313468Y-268420D01*
X314778Y-267545D01*
X315870Y-266379D01*
G01X331841Y-269003D02*
Y-257337D01*
G01Y-259378D02*
X330968Y-258212D01*
X329657Y-257628D01*
X328129Y-257337D01*
X326601Y-257920D01*
X325291Y-259086D01*
X324417Y-260836D01*
X323981Y-263170D01*
X324417Y-265503D01*
X325291Y-267253D01*
X326601Y-268420D01*
X328129Y-269003D01*
X329657Y-268711D01*
X330968Y-267837D01*
X331841Y-266670D01*
G01X342354Y-269003D02*
Y-257337D01*
G01Y-259670D02*
X343446Y-258503D01*
X344538Y-257628D01*
X346066Y-257337D01*
X347157Y-257628D01*
X348468Y-258503D01*
G01X366841Y-251503D02*
Y-269003D01*
G01Y-266379D02*
X365968Y-267837D01*
X364657Y-268711D01*
X363129Y-269003D01*
X361383Y-268420D01*
X360073Y-266962D01*
X359199Y-265212D01*
X358981Y-263170D01*
X359199Y-261128D01*
X360073Y-259378D01*
X361383Y-257920D01*
X363129Y-257337D01*
X364657Y-257628D01*
X365749Y-258212D01*
X366841Y-259378D01*
G01X68484Y-224003D02*
Y-206503D01*
X74161Y-221086D01*
X79838Y-206503D01*
Y-224003D01*
G01X91661D02*
X90351Y-223711D01*
X89041Y-222545D01*
X88167Y-220503D01*
X87731Y-218170D01*
X88167Y-215836D01*
X89041Y-213795D01*
X90351Y-212628D01*
X91661Y-212337D01*
X92971Y-212628D01*
X94281Y-213795D01*
X95154Y-215836D01*
X95373Y-218170D01*
X95154Y-220503D01*
X94281Y-222545D01*
X92971Y-223711D01*
X91661Y-224003D01*
G01X113091Y-206503D02*
Y-224003D01*
G01Y-221379D02*
X112218Y-222837D01*
X110907Y-223711D01*
X109379Y-224003D01*
X107633Y-223420D01*
X106323Y-221962D01*
X105449Y-220212D01*
X105231Y-218170D01*
X105449Y-216128D01*
X106323Y-214378D01*
X107633Y-212920D01*
X109379Y-212337D01*
X110907Y-212628D01*
X111999Y-213212D01*
X113091Y-214378D01*
G01X123386Y-216128D02*
X130373D01*
X129718Y-214086D01*
X128626Y-212920D01*
X127098Y-212337D01*
X125569Y-212628D01*
X124259Y-213503D01*
X123386Y-215545D01*
X122949Y-217295D01*
Y-219045D01*
X123386Y-220795D01*
X124478Y-222545D01*
X125788Y-223711D01*
X127316Y-224003D01*
X128844Y-223420D01*
X130373Y-221670D01*
G01X144161Y-224003D02*
Y-206503D01*
G01X424761Y-269003D02*
Y-251503D01*
X422141Y-255003D01*
G01Y-269003D02*
X427381D01*
G01X437458Y-266379D02*
X438767Y-267837D01*
X440296Y-268711D01*
X442261Y-269003D01*
X444226Y-268420D01*
X445754Y-267253D01*
X446846Y-265212D01*
X447064Y-262878D01*
X446628Y-260545D01*
X445536Y-259086D01*
X444007Y-257920D01*
X442479Y-257628D01*
X440951Y-257920D01*
X438986Y-259086D01*
X439641Y-251503D01*
X445536D01*
G01X459324Y-269003D02*
X459761Y-265212D01*
X460416Y-262003D01*
X461289Y-259086D01*
X462381Y-255878D01*
X464128Y-251503D01*
X455394D01*
G01X472458Y-266379D02*
X473767Y-267837D01*
X475296Y-268711D01*
X477261Y-269003D01*
X479226Y-268420D01*
X480754Y-267253D01*
X481846Y-265212D01*
X482064Y-262878D01*
X481628Y-260545D01*
X480536Y-259086D01*
X479007Y-257920D01*
X477479Y-257628D01*
X475951Y-257920D01*
X473986Y-259086D01*
X474641Y-251503D01*
X480536D01*
G01X494761D02*
X493014Y-252086D01*
X491704Y-253545D01*
X490831Y-255294D01*
X490176Y-257628D01*
X489958Y-260253D01*
X490176Y-262878D01*
X490831Y-265212D01*
X491704Y-266962D01*
X493014Y-268420D01*
X494761Y-269003D01*
X496507Y-268420D01*
X497818Y-266962D01*
X498691Y-265212D01*
X499346Y-262878D01*
X499564Y-260253D01*
X499346Y-257628D01*
X498691Y-255294D01*
X497818Y-253545D01*
X496507Y-252086D01*
X494761Y-251503D01*
G01X411644Y-224003D02*
Y-206503D01*
X416884D01*
X418631Y-207378D01*
X419941Y-209420D01*
X420378Y-211753D01*
X419941Y-214086D01*
X418849Y-215836D01*
X416884Y-216712D01*
X411644D01*
G01X438314Y-207962D02*
X437004Y-207086D01*
X435476Y-206503D01*
X433729D01*
X431764Y-207378D01*
X430236Y-208836D01*
X429144Y-210587D01*
X428271Y-213503D01*
X428052Y-216128D01*
X428489Y-218753D01*
X429144Y-220503D01*
X430454Y-222253D01*
X431983Y-223420D01*
X433511Y-224003D01*
X435039D01*
X436568Y-223420D01*
X437878Y-222545D01*
X438970Y-221379D01*
G01X452757Y-214670D02*
X453631Y-213795D01*
X454286Y-212337D01*
X454723Y-210294D01*
X454286Y-208545D01*
X453413Y-207378D01*
X451884Y-206503D01*
X445989D01*
Y-224003D01*
X453194D01*
X454723Y-222837D01*
X455596Y-221086D01*
X456033Y-219045D01*
X455596Y-217003D01*
X454286Y-215253D01*
X452757Y-214670D01*
X445989D01*
G01X461961Y-229836D02*
X475061D01*
G01X480989Y-224003D02*
Y-206503D01*
X491033Y-224003D01*
Y-206503D01*
G01X503511Y-224003D02*
X501764Y-223711D01*
X500236Y-222545D01*
X498926Y-220795D01*
X498052Y-218753D01*
X497616Y-216420D01*
Y-214086D01*
X498052Y-211753D01*
X498926Y-209711D01*
X500236Y-207962D01*
X501764Y-206795D01*
X503511Y-206503D01*
X505257Y-206795D01*
X506786Y-207962D01*
X508096Y-209711D01*
X508970Y-211753D01*
X509406Y-214086D01*
Y-216420D01*
X508970Y-218753D01*
X508096Y-220795D01*
X506786Y-222545D01*
X505257Y-223711D01*
X503511Y-224003D01*
G01X554352Y-206503D02*
X559811Y-224003D01*
X565270Y-206503D01*
G01X581678Y-224003D02*
X572944D01*
Y-206503D01*
X581678D01*
G01X578184Y-214961D02*
X572944D01*
G01X590444Y-224003D02*
Y-206503D01*
X595903D01*
X597649Y-207378D01*
X598741Y-208545D01*
X599178Y-210878D01*
X598741Y-213212D01*
X597431Y-214670D01*
X595903Y-215545D01*
X590444D01*
G01X595903D02*
X599178Y-224003D01*
G01X612311Y-224586D02*
X611874Y-224295D01*
Y-223711D01*
X612311Y-223420D01*
X612748Y-223711D01*
Y-224295D01*
X612311Y-224586D01*
G01X586061Y-269003D02*
Y-251503D01*
X583441Y-255003D01*
G01Y-269003D02*
X588681D01*
G01X766628Y-251503D02*
Y-269003D01*
X757894D01*
G01X745198D02*
X744761Y-265212D01*
X744106Y-262003D01*
X743233Y-259086D01*
X742141Y-255878D01*
X740394Y-251503D01*
X749128D01*
G01X725951Y-260253D02*
X721584D01*
Y-265503D01*
X722894Y-267253D01*
X724423Y-268420D01*
X726606Y-269003D01*
X728789Y-268420D01*
X730318Y-267253D01*
X731628Y-265503D01*
X732501Y-263461D01*
X732938Y-261128D01*
Y-259086D01*
X732501Y-257337D01*
X731628Y-255294D01*
X730318Y-253545D01*
X729008Y-252378D01*
X727261Y-251503D01*
X725733D01*
X723986Y-252086D01*
X722676Y-253253D01*
G01X714783Y-269003D02*
Y-251503D01*
X704739Y-269003D01*
Y-251503D01*
G01X697064Y-269003D02*
Y-251503D01*
X692698D01*
X690951Y-252378D01*
X689641Y-253545D01*
X688549Y-255294D01*
X687676Y-257337D01*
X687458Y-260253D01*
X687676Y-263170D01*
X688549Y-265212D01*
X689641Y-266962D01*
X690951Y-268128D01*
X692698Y-269003D01*
X697064D01*
G01X687894Y-206503D02*
Y-224003D01*
X696628D01*
G01X713691D02*
Y-212337D01*
G01Y-214378D02*
X712818Y-213212D01*
X711507Y-212628D01*
X709979Y-212337D01*
X708451Y-212920D01*
X707141Y-214086D01*
X706267Y-215836D01*
X705831Y-218170D01*
X706267Y-220503D01*
X707141Y-222253D01*
X708451Y-223420D01*
X709979Y-224003D01*
X711507Y-223711D01*
X712818Y-222837D01*
X713691Y-221670D01*
G01X722676Y-229253D02*
X723986Y-229836D01*
X725733Y-229253D01*
X726824Y-228087D01*
X727698Y-226628D01*
X729007Y-221962D01*
X731846Y-212337D01*
G01X724859D02*
X729007Y-221962D01*
G01X741486Y-216128D02*
X748473D01*
X747818Y-214086D01*
X746726Y-212920D01*
X745198Y-212337D01*
X743669Y-212628D01*
X742359Y-213503D01*
X741486Y-215545D01*
X741049Y-217295D01*
Y-219045D01*
X741486Y-220795D01*
X742578Y-222545D01*
X743888Y-223711D01*
X745416Y-224003D01*
X746944Y-223420D01*
X748473Y-221670D01*
G01X759204Y-224003D02*
Y-212337D01*
G01Y-214670D02*
X760296Y-213503D01*
X761388Y-212628D01*
X762916Y-212337D01*
X764007Y-212628D01*
X765318Y-213503D01*
G01X830008Y-224003D02*
Y-206503D01*
X834374D01*
X836121Y-207378D01*
X837431Y-208545D01*
X838523Y-210294D01*
X839396Y-212337D01*
X839614Y-215253D01*
X839396Y-218170D01*
X838523Y-220212D01*
X837431Y-221962D01*
X836121Y-223128D01*
X834374Y-224003D01*
X830008D01*
G01X849036Y-216128D02*
X856023D01*
X855368Y-214086D01*
X854276Y-212920D01*
X852748Y-212337D01*
X851219Y-212628D01*
X849909Y-213503D01*
X849036Y-215545D01*
X848599Y-217295D01*
Y-219045D01*
X849036Y-220795D01*
X850128Y-222545D01*
X851438Y-223711D01*
X852966Y-224003D01*
X854494Y-223420D01*
X856023Y-221670D01*
G01X866536Y-221962D02*
X867628Y-223128D01*
X869156Y-224003D01*
X870466D01*
X871776Y-223420D01*
X872649Y-222545D01*
X873086Y-221379D01*
X872868Y-219628D01*
X871994Y-218753D01*
X868064Y-217003D01*
X867191Y-214961D01*
X867628Y-213503D01*
X868501Y-212628D01*
X869811Y-212337D01*
X871121Y-212628D01*
X872431Y-213503D01*
G01X887311Y-212337D02*
Y-224003D01*
G01Y-207670D02*
X886874Y-207378D01*
Y-206795D01*
X887311Y-206503D01*
X887748Y-206795D01*
Y-207378D01*
X887311Y-207670D01*
G01X901754Y-228378D02*
X903283Y-229545D01*
X905029Y-229836D01*
X906557Y-229545D01*
X907868Y-228087D01*
X908741Y-226045D01*
Y-212337D01*
G01Y-214670D02*
X907868Y-213503D01*
X906557Y-212628D01*
X905029Y-212337D01*
X903283Y-212920D01*
X902191Y-214086D01*
X901317Y-216128D01*
X900881Y-218170D01*
X901099Y-219920D01*
X901973Y-221962D01*
X903283Y-223420D01*
X905029Y-224003D01*
X906339Y-223711D01*
X907868Y-222545D01*
X908741Y-221379D01*
G01X918599Y-224003D02*
Y-212337D01*
G01Y-215253D02*
X919473Y-213795D01*
X920783Y-212628D01*
X922529Y-212337D01*
X924057Y-212628D01*
X925368Y-213795D01*
X926023Y-215836D01*
Y-224003D01*
G01X936536Y-216128D02*
X943523D01*
X942868Y-214086D01*
X941776Y-212920D01*
X940248Y-212337D01*
X938719Y-212628D01*
X937409Y-213503D01*
X936536Y-215545D01*
X936099Y-217295D01*
Y-219045D01*
X936536Y-220795D01*
X937628Y-222545D01*
X938938Y-223711D01*
X940466Y-224003D01*
X941994Y-223420D01*
X943523Y-221670D01*
G01X954254Y-224003D02*
Y-212337D01*
G01Y-214670D02*
X955346Y-213503D01*
X956438Y-212628D01*
X957966Y-212337D01*
X959057Y-212628D01*
X960368Y-213503D01*
G01X874194Y-265503D02*
X875286Y-267253D01*
X876596Y-268420D01*
X878124Y-269003D01*
X879871Y-268420D01*
X881181Y-267253D01*
X882491Y-265503D01*
X882928Y-263170D01*
Y-251503D01*
G01X896061Y-269003D02*
X894314Y-268711D01*
X892786Y-267545D01*
X891476Y-265795D01*
X890602Y-263753D01*
X890166Y-261420D01*
Y-259086D01*
X890602Y-256753D01*
X891476Y-254711D01*
X892786Y-252962D01*
X894314Y-251795D01*
X896061Y-251503D01*
X897807Y-251795D01*
X899336Y-252962D01*
X900646Y-254711D01*
X901520Y-256753D01*
X901956Y-259086D01*
Y-261420D01*
X901520Y-263753D01*
X900646Y-265795D01*
X899336Y-267545D01*
X897807Y-268711D01*
X896061Y-269003D01*
G01X913561D02*
Y-261128D01*
X909194Y-251503D01*
G01X917928D02*
X913561Y-261128D01*
G01X1001011Y-269003D02*
Y-251503D01*
X998391Y-255003D01*
G01Y-269003D02*
X1003631D01*
G01X1014363Y-254420D02*
X1015673Y-252670D01*
X1017201Y-251795D01*
X1018948Y-251503D01*
X1021131Y-252086D01*
X1022659Y-253545D01*
X1023096Y-255294D01*
X1022878Y-257045D01*
X1022004Y-258503D01*
X1017638Y-261420D01*
X1015673Y-263461D01*
X1014363Y-266379D01*
X1013926Y-269003D01*
X1023096D01*
G01X1032081Y-269586D02*
X1039941Y-251503D01*
G01X1048708Y-265503D02*
X1050017Y-267545D01*
X1051764Y-268711D01*
X1053729Y-269003D01*
X1055476Y-268711D01*
X1057223Y-267253D01*
X1058314Y-265503D01*
X1058533Y-263753D01*
X1058096Y-261712D01*
X1056568Y-260253D01*
X1055039Y-259670D01*
X1053074D01*
G01X1055039D02*
X1056349Y-258795D01*
X1057441Y-257337D01*
X1057878Y-255587D01*
X1057441Y-253836D01*
X1056349Y-252378D01*
X1054384Y-251503D01*
X1052419Y-251795D01*
X1050454Y-252962D01*
G01X1071011Y-251503D02*
X1069264Y-252086D01*
X1067954Y-253545D01*
X1067081Y-255294D01*
X1066426Y-257628D01*
X1066208Y-260253D01*
X1066426Y-262878D01*
X1067081Y-265212D01*
X1067954Y-266962D01*
X1069264Y-268420D01*
X1071011Y-269003D01*
X1072757Y-268420D01*
X1074068Y-266962D01*
X1074941Y-265212D01*
X1075596Y-262878D01*
X1075814Y-260253D01*
X1075596Y-257628D01*
X1074941Y-255294D01*
X1074068Y-253545D01*
X1072757Y-252086D01*
X1071011Y-251503D01*
G01X1084581Y-269586D02*
X1092441Y-251503D01*
G01X1101863Y-254420D02*
X1103173Y-252670D01*
X1104701Y-251795D01*
X1106448Y-251503D01*
X1108631Y-252086D01*
X1110159Y-253545D01*
X1110596Y-255294D01*
X1110378Y-257045D01*
X1109504Y-258503D01*
X1105138Y-261420D01*
X1103173Y-263461D01*
X1101863Y-266379D01*
X1101426Y-269003D01*
X1110596D01*
G01X1123511Y-251503D02*
X1121764Y-252086D01*
X1120454Y-253545D01*
X1119581Y-255294D01*
X1118926Y-257628D01*
X1118708Y-260253D01*
X1118926Y-262878D01*
X1119581Y-265212D01*
X1120454Y-266962D01*
X1121764Y-268420D01*
X1123511Y-269003D01*
X1125257Y-268420D01*
X1126568Y-266962D01*
X1127441Y-265212D01*
X1128096Y-262878D01*
X1128314Y-260253D01*
X1128096Y-257628D01*
X1127441Y-255294D01*
X1126568Y-253545D01*
X1125257Y-252086D01*
X1123511Y-251503D01*
G01X1141011Y-269003D02*
Y-251503D01*
X1138391Y-255003D01*
G01Y-269003D02*
X1143631D01*
G01X1154363Y-261712D02*
X1155891Y-259670D01*
X1157201Y-258503D01*
X1158948Y-257920D01*
X1160476Y-258503D01*
X1161568Y-259670D01*
X1162441Y-261420D01*
X1162659Y-263461D01*
X1162441Y-265212D01*
X1161568Y-266962D01*
X1160257Y-268420D01*
X1158729Y-269003D01*
X1156983Y-268420D01*
X1155454Y-266670D01*
X1154581Y-264045D01*
X1154363Y-261128D01*
X1154799Y-257337D01*
X1155454Y-255294D01*
X1156546Y-253253D01*
X1158074Y-251795D01*
X1159603Y-251503D01*
X1161131Y-252086D01*
X1162223Y-253545D01*
G01X1048708Y-224003D02*
Y-206503D01*
X1053074D01*
X1054821Y-207378D01*
X1056131Y-208545D01*
X1057223Y-210294D01*
X1058096Y-212337D01*
X1058314Y-215253D01*
X1058096Y-218170D01*
X1057223Y-220212D01*
X1056131Y-221962D01*
X1054821Y-223128D01*
X1053074Y-224003D01*
X1048708D01*
G01X1074941D02*
Y-212337D01*
G01Y-214378D02*
X1074068Y-213212D01*
X1072757Y-212628D01*
X1071229Y-212337D01*
X1069701Y-212920D01*
X1068391Y-214086D01*
X1067517Y-215836D01*
X1067081Y-218170D01*
X1067517Y-220503D01*
X1068391Y-222253D01*
X1069701Y-223420D01*
X1071229Y-224003D01*
X1072757Y-223711D01*
X1074068Y-222837D01*
X1074941Y-221670D01*
G01X1088511Y-206503D02*
Y-224003D01*
G01X1085454Y-212337D02*
X1091568D01*
G01X1102736Y-216128D02*
X1109723D01*
X1109068Y-214086D01*
X1107976Y-212920D01*
X1106448Y-212337D01*
X1104919Y-212628D01*
X1103609Y-213503D01*
X1102736Y-215545D01*
X1102299Y-217295D01*
Y-219045D01*
X1102736Y-220795D01*
X1103828Y-222545D01*
X1105138Y-223711D01*
X1106666Y-224003D01*
X1108194Y-223420D01*
X1109723Y-221670D01*
M02*
